(kicad_pcb
	(version 20260206)
	(generator "pcbnew")
	(generator_version "10.0")
	(general
		(thickness 1.6)
		(legacy_teardrops no)
	)
	(paper "A4")
	(title_block
		(title "netronome-mezz — pcbd0082-001_rev01_jul9_a.brd")
		(comment 1 "Open CloudServer (Microsoft) / footprints 120-128 of 714")
	)
	(layers
		(0 "F.Cu" signal "TOP")
		(4 "In1.Cu" signal "02_GND")
		(6 "In2.Cu" signal "03_SIG")
		(8 "In3.Cu" signal "04_SIG")
		(10 "In4.Cu" signal "05_GND")
		(12 "In5.Cu" signal "06_PWR1")
		(14 "In6.Cu" signal "07_SIG")
		(16 "In7.Cu" signal "08_SIG")
		(18 "In8.Cu" signal "09_GND")
		(2 "B.Cu" signal "BOTTOM")
		(9 "F.Adhes" user "F.Adhesive")
		(11 "B.Adhes" user "B.Adhesive")
		(13 "F.Paste" user "Package Geometry/Pastemask Top")
		(15 "B.Paste" user "Package Geometry/Pastemask Bottom")
		(5 "F.SilkS" user "Ref Des/Silkscreen Top")
		(7 "B.SilkS" user "Ref Des/Silkscreen Bottom")
		(1 "F.Mask" user "Board Geometry/Soldermask Top")
		(3 "B.Mask" user "Board Geometry/Soldermask Bottom")
		(17 "Dwgs.User" user "User.Drawings")
		(19 "Cmts.User" user "User.Comments")
		(21 "Eco1.User" user "User.Eco1")
		(23 "Eco2.User" user "User.Eco2")
		(25 "Edge.Cuts" user "Board Geometry/Outline")
		(27 "Margin" user)
		(31 "F.CrtYd" user "Package Geometry/Place Bound Top")
		(29 "B.CrtYd" user "Package Geometry/Place Bound Bottom")
		(35 "F.Fab" user "Ref Des/Assembly Top")
		(33 "B.Fab" user "Ref Des/Assembly Bottom")
		(45 "User.4" user "COMPVAL_TYPE_BOTTOM")
	)
	(footprint ""
		(layer "F.Cu")
		(at 36.322 39.878 90)
		(property "Reference" "R325"
			(at 0 0 90)
			(layer "F.SilkS")
			(hide yes)
			(effects
				(font
					(size 1.27 1.27)
				)
			)
		)
		(property "Value" "86.6K"
			(at -0.148158 1.3462 180)
			(unlocked yes)
			(layer "F.Fab")
			(hide yes)
			(effects
				(font
					(size 1.27 0.9652)
					(thickness 0.000001)
				)
				(justify left)
			)
		)
		(property "Device Type" "REST0029"
			(at -0.148158 1.3462 180)
			(unlocked yes)
			(layer "F.Fab")
			(hide yes)
			(effects
				(font
					(size 1.27 0.9652)
					(thickness 0.000001)
				)
				(justify left)
			)
		)
		(duplicate_pad_numbers_are_jumpers no)
		(fp_poly
			(pts
				(xy 0.635 1.0668) (xy 0.635 -1.0668) (xy -0.635 -1.0668) (xy -0.635 1.0668)
			)
			(stroke
				(width 0)
				(type default)
			)
			(fill no)
			(layer "F.CrtYd")
		)
		(fp_line
			(start 0.254 -0.508)
			(end 0.254 0.508)
			(stroke
				(width 0.0254)
				(type default)
			)
			(layer "F.Fab")
		)
		(fp_line
			(start -0.254 -0.508)
			(end 0.254 -0.508)
			(stroke
				(width 0.0254)
				(type default)
			)
			(layer "F.Fab")
		)
		(fp_line
			(start 0.254 0.508)
			(end -0.254 0.508)
			(stroke
				(width 0.0254)
				(type default)
			)
			(layer "F.Fab")
		)
		(fp_line
			(start -0.254 0.508)
			(end -0.254 -0.508)
			(stroke
				(width 0.0254)
				(type default)
			)
			(layer "F.Fab")
		)
		(pad "1" smd rect
			(at 0 -0.4191 90)
			(size 0.508 0.5334)
			(layers "F.Cu" "F.Mask" "F.Paste")
			(net "10N2528")
		)
		(pad "2" smd rect
			(at 0 0.4191 90)
			(size 0.508 0.5334)
			(layers "F.Cu" "F.Mask" "F.Paste")
			(net "NFP_VDD_CORE_ISEN1_P")
		)
		(zone
			(layer "F.Cu")
			(hatch none 0.5)
			(connect_pads
				(clearance 0)
			)
			(min_thickness 0.25)
			(keepout
				(tracks not_allowed)
				(vias allowed)
				(pads allowed)
				(copperpour not_allowed)
				(footprints allowed)
			)
			(placement
				(enabled no)
				(sheetname "")
			)
			(fill
				(thermal_gap 0.5)
				(thermal_bridge_width 0.5)
				(island_removal_mode 0)
			)
			(polygon
				(pts
					(xy 36.2966 39.8526) (xy 36.3474 39.8526) (xy 36.3474 39.9034) (xy 36.2966 39.9034)
				)
			)
		)
	)
	(footprint ""
		(layer "F.Cu")
		(at 36.322 36.195 90)
		(property "Reference" "R180"
			(at 0 0 90)
			(layer "F.SilkS")
			(hide yes)
			(effects
				(font
					(size 1.27 1.27)
				)
			)
		)
		(property "Value" "0"
			(at -0.148158 1.3462 180)
			(unlocked yes)
			(layer "F.Fab")
			(hide yes)
			(effects
				(font
					(size 1.27 0.9652)
					(thickness 0.000001)
				)
				(justify left)
			)
		)
		(property "Device Type" "REST1111"
			(at -0.148158 1.3462 180)
			(unlocked yes)
			(layer "F.Fab")
			(hide yes)
			(effects
				(font
					(size 1.27 0.9652)
					(thickness 0.000001)
				)
				(justify left)
			)
		)
		(duplicate_pad_numbers_are_jumpers no)
		(fp_poly
			(pts
				(xy 0.635 1.0668) (xy 0.635 -1.0668) (xy -0.635 -1.0668) (xy -0.635 1.0668)
			)
			(stroke
				(width 0)
				(type default)
			)
			(fill no)
			(layer "F.CrtYd")
		)
		(fp_line
			(start 0.254 -0.508)
			(end 0.254 0.508)
			(stroke
				(width 0.0254)
				(type default)
			)
			(layer "F.Fab")
		)
		(fp_line
			(start -0.254 -0.508)
			(end 0.254 -0.508)
			(stroke
				(width 0.0254)
				(type default)
			)
			(layer "F.Fab")
		)
		(fp_line
			(start 0.254 0.508)
			(end -0.254 0.508)
			(stroke
				(width 0.0254)
				(type default)
			)
			(layer "F.Fab")
		)
		(fp_line
			(start -0.254 0.508)
			(end -0.254 -0.508)
			(stroke
				(width 0.0254)
				(type default)
			)
			(layer "F.Fab")
		)
		(pad "1" smd rect
			(at 0 -0.4191 90)
			(size 0.508 0.5334)
			(layers "F.Cu" "F.Mask" "F.Paste")
			(net "10N2409")
		)
		(pad "2" smd rect
			(at 0 0.4191 90)
			(size 0.508 0.5334)
			(layers "F.Cu" "F.Mask" "F.Paste")
			(net "VDD_5.0V")
		)
		(zone
			(layer "F.Cu")
			(hatch none 0.5)
			(connect_pads
				(clearance 0)
			)
			(min_thickness 0.25)
			(keepout
				(tracks not_allowed)
				(vias allowed)
				(pads allowed)
				(copperpour not_allowed)
				(footprints allowed)
			)
			(placement
				(enabled no)
				(sheetname "")
			)
			(fill
				(thermal_gap 0.5)
				(thermal_bridge_width 0.5)
				(island_removal_mode 0)
			)
			(polygon
				(pts
					(xy 36.2966 36.1696) (xy 36.3474 36.1696) (xy 36.3474 36.2204) (xy 36.2966 36.2204)
				)
			)
		)
	)
	(footprint ""
		(layer "F.Cu")
		(at 15.748 29.0195 -90)
		(property "Reference" "TP55"
			(at -0.889 0.86233 90)
			(unlocked yes)
			(layer "F.SilkS")
			(effects
				(font
					(size 0.7874 0.5842)
					(thickness 0.127)
				)
				(justify left)
			)
		)
		(property "Value" "*"
			(at -0.4826 -0.14732 270)
			(unlocked yes)
			(layer "F.Fab")
			(hide yes)
			(effects
				(font
					(size 1.27 0.9652)
					(thickness 0.000001)
				)
				(justify left)
			)
		)
		(property "Device Type" "TP_SMALL"
			(at -0.4826 -0.14732 270)
			(unlocked yes)
			(layer "F.Fab")
			(hide yes)
			(effects
				(font
					(size 1.27 0.9652)
					(thickness 0.000001)
				)
				(justify left)
			)
		)
		(duplicate_pad_numbers_are_jumpers no)
		(fp_line
			(start -0.8636 0.8636)
			(end 0.8636 0.8636)
			(stroke
				(width 0.1524)
				(type default)
			)
			(layer "F.SilkS")
		)
		(fp_line
			(start 0.8636 0.8636)
			(end 0.8636 -0.8636)
			(stroke
				(width 0.1524)
				(type default)
			)
			(layer "F.SilkS")
		)
		(fp_line
			(start -0.8636 -0.8636)
			(end -0.8636 0.8636)
			(stroke
				(width 0.1524)
				(type default)
			)
			(layer "F.SilkS")
		)
		(fp_line
			(start 0.8636 -0.8636)
			(end -0.8636 -0.8636)
			(stroke
				(width 0.1524)
				(type default)
			)
			(layer "F.SilkS")
		)
		(fp_poly
			(pts
				(xy -0.635 -0.635) (xy -0.635 0.635) (xy 0.635 0.635) (xy 0.635 -0.635)
			)
			(stroke
				(width 0)
				(type default)
			)
			(fill no)
			(layer "F.CrtYd")
		)
		(pad "1" smd rect
			(at 0 0 270)
			(size 1.27 1.27)
			(layers "F.Cu" "F.Mask" "F.Paste")
			(net "GND")
		)
	)
	(footprint ""
		(layer "F.Cu")
		(at 19.7739 42.9641)
		(property "Reference" "L12"
			(at -1.651 2.05867 0)
			(unlocked yes)
			(layer "F.SilkS")
			(effects
				(font
					(size 0.7874 0.5842)
					(thickness 0.127)
				)
				(justify left)
			)
		)
		(property "Value" "2.2UH"
			(at -0.483362 -0.148082 0)
			(unlocked yes)
			(layer "F.Fab")
			(hide yes)
			(effects
				(font
					(size 1.27 0.9652)
					(thickness 0.000001)
				)
				(justify left)
			)
		)
		(property "Device Type" "INDS0060"
			(at -0.483362 -0.148082 0)
			(unlocked yes)
			(layer "F.Fab")
			(hide yes)
			(effects
				(font
					(size 1.27 0.9652)
					(thickness 0.000001)
				)
				(justify left)
			)
		)
		(duplicate_pad_numbers_are_jumpers no)
		(fp_line
			(start -1.27 -1.397)
			(end 1.27 -1.397)
			(stroke
				(width 0.1524)
				(type default)
			)
			(layer "F.SilkS")
		)
		(fp_line
			(start 1.27 1.397)
			(end -1.27 1.397)
			(stroke
				(width 0.1524)
				(type default)
			)
			(layer "F.SilkS")
		)
		(fp_poly
			(pts
				(xy 2.159 -1.651) (xy 2.159 1.651) (xy -2.159 1.651) (xy -2.159 -1.651)
			)
			(stroke
				(width 0)
				(type default)
			)
			(fill no)
			(layer "F.CrtYd")
		)
		(fp_line
			(start -1.3462 -1.1049)
			(end -1.3462 1.1049)
			(stroke
				(width 0.1524)
				(type default)
			)
			(layer "F.Fab")
		)
		(fp_line
			(start -1.3462 1.1049)
			(end 1.3462 1.1049)
			(stroke
				(width 0.1524)
				(type default)
			)
			(layer "F.Fab")
		)
		(fp_line
			(start 1.3462 -1.1049)
			(end -1.3462 -1.1049)
			(stroke
				(width 0.1524)
				(type default)
			)
			(layer "F.Fab")
		)
		(fp_line
			(start 1.3462 1.1049)
			(end 1.3462 -1.1049)
			(stroke
				(width 0.1524)
				(type default)
			)
			(layer "F.Fab")
		)
		(pad "1" smd rect
			(at -1.1303 0)
			(size 1.1938 2.3368)
			(layers "F.Cu" "F.Mask" "F.Paste")
			(net "11N1971")
		)
		(pad "2" smd rect
			(at 1.1303 0)
			(size 1.1938 2.3368)
			(layers "F.Cu" "F.Mask" "F.Paste")
			(net "DDR_1.8V")
		)
		(zone
			(layer "F.Cu")
			(hatch none 0.5)
			(connect_pads
				(clearance 0)
			)
			(min_thickness 0.25)
			(keepout
				(tracks allowed)
				(vias not_allowed)
				(pads allowed)
				(copperpour not_allowed)
				(footprints allowed)
			)
			(placement
				(enabled no)
				(sheetname "")
			)
			(fill
				(thermal_gap 0.5)
				(thermal_bridge_width 0.5)
				(island_removal_mode 0)
			)
			(polygon
				(pts
					(xy 18.4277 44.069) (xy 21.1201 44.069) (xy 21.1201 41.8592) (xy 18.4277 41.8592)
				)
			)
		)
	)
	(footprint ""
		(layer "F.Cu")
		(at 3.302 34.163 180)
		(property "Reference" "R130"
			(at 0 0 180)
			(layer "F.SilkS")
			(hide yes)
			(effects
				(font
					(size 1.27 1.27)
				)
			)
		)
		(property "Value" "2K"
			(at -0.148158 1.3462 270)
			(unlocked yes)
			(layer "F.Fab")
			(hide yes)
			(effects
				(font
					(size 1.27 0.9652)
					(thickness 0.000001)
				)
				(justify left)
			)
		)
		(property "Device Type" "REST0138"
			(at -0.148158 1.3462 270)
			(unlocked yes)
			(layer "F.Fab")
			(hide yes)
			(effects
				(font
					(size 1.27 0.9652)
					(thickness 0.000001)
				)
				(justify left)
			)
		)
		(duplicate_pad_numbers_are_jumpers no)
		(fp_poly
			(pts
				(xy 0.635 1.0668) (xy 0.635 -1.0668) (xy -0.635 -1.0668) (xy -0.635 1.0668)
			)
			(stroke
				(width 0)
				(type default)
			)
			(fill no)
			(layer "F.CrtYd")
		)
		(fp_line
			(start 0.254 0.508)
			(end -0.254 0.508)
			(stroke
				(width 0.0254)
				(type default)
			)
			(layer "F.Fab")
		)
		(fp_line
			(start 0.254 -0.508)
			(end 0.254 0.508)
			(stroke
				(width 0.0254)
				(type default)
			)
			(layer "F.Fab")
		)
		(fp_line
			(start -0.254 0.508)
			(end -0.254 -0.508)
			(stroke
				(width 0.0254)
				(type default)
			)
			(layer "F.Fab")
		)
		(fp_line
			(start -0.254 -0.508)
			(end 0.254 -0.508)
			(stroke
				(width 0.0254)
				(type default)
			)
			(layer "F.Fab")
		)
		(pad "1" smd rect
			(at 0 -0.4191 180)
			(size 0.508 0.5334)
			(layers "F.Cu" "F.Mask" "F.Paste")
			(net "PSU_I2C_SDA")
		)
		(pad "2" smd rect
			(at 0 0.4191 180)
			(size 0.508 0.5334)
			(layers "F.Cu" "F.Mask" "F.Paste")
			(net "EXT_3.3V")
		)
		(zone
			(layer "F.Cu")
			(hatch none 0.5)
			(connect_pads
				(clearance 0)
			)
			(min_thickness 0.25)
			(keepout
				(tracks not_allowed)
				(vias allowed)
				(pads allowed)
				(copperpour not_allowed)
				(footprints allowed)
			)
			(placement
				(enabled no)
				(sheetname "")
			)
			(fill
				(thermal_gap 0.5)
				(thermal_bridge_width 0.5)
				(island_removal_mode 0)
			)
			(polygon
				(pts
					(xy 3.2766 34.1884) (xy 3.2766 34.1376) (xy 3.3274 34.1376) (xy 3.3274 34.1884)
				)
			)
		)
	)
	(footprint ""
		(layer "F.Cu")
		(at 37.719 41.656 180)
		(property "Reference" "R401"
			(at 0 0 180)
			(layer "F.SilkS")
			(hide yes)
			(effects
				(font
					(size 1.27 1.27)
				)
			)
		)
		(property "Value" "680"
			(at -0.148158 1.7526 270)
			(unlocked yes)
			(layer "F.Fab")
			(hide yes)
			(effects
				(font
					(size 1.27 0.9652)
					(thickness 0.000001)
				)
				(justify left)
			)
		)
		(property "Device Type" "REST0283"
			(at -0.148158 1.7526 270)
			(unlocked yes)
			(layer "F.Fab")
			(hide yes)
			(effects
				(font
					(size 1.27 0.9652)
					(thickness 0.000001)
				)
				(justify left)
			)
		)
		(duplicate_pad_numbers_are_jumpers no)
		(fp_circle
			(center 0 0)
			(end -0.127 0)
			(stroke
				(width 0.2032)
				(type default)
			)
			(fill no)
			(layer "F.SilkS")
		)
		(fp_poly
			(pts
				(xy 0.7874 -1.6637) (xy -0.7874 -1.6637) (xy -0.7874 1.6637) (xy 0.7874 1.6637)
			)
			(stroke
				(width 0)
				(type default)
			)
			(fill no)
			(layer "F.CrtYd")
		)
		(fp_line
			(start 0.4064 0.8128)
			(end -0.4064 0.8128)
			(stroke
				(width 0.0254)
				(type default)
			)
			(layer "F.Fab")
		)
		(fp_line
			(start 0.4064 -0.8128)
			(end 0.4064 0.8128)
			(stroke
				(width 0.0254)
				(type default)
			)
			(layer "F.Fab")
		)
		(fp_line
			(start -0.4064 0.8128)
			(end -0.4064 -0.8128)
			(stroke
				(width 0.0254)
				(type default)
			)
			(layer "F.Fab")
		)
		(fp_line
			(start -0.4064 -0.8128)
			(end 0.4064 -0.8128)
			(stroke
				(width 0.0254)
				(type default)
			)
			(layer "F.Fab")
		)
		(pad "1" smd rect
			(at 0 -0.8001 180)
			(size 0.762 0.9652)
			(layers "F.Cu" "F.Mask" "F.Paste")
			(net "EXT_12.0V")
		)
		(pad "2" smd rect
			(at 0 0.8001 180)
			(size 0.762 0.9652)
			(layers "F.Cu" "F.Mask" "F.Paste")
			(net "10N2370")
		)
		(zone
			(layer "F.Cu")
			(hatch none 0.5)
			(connect_pads
				(clearance 0)
			)
			(min_thickness 0.25)
			(keepout
				(tracks not_allowed)
				(vias allowed)
				(pads allowed)
				(copperpour not_allowed)
				(footprints allowed)
			)
			(placement
				(enabled no)
				(sheetname "")
			)
			(fill
				(thermal_gap 0.5)
				(thermal_bridge_width 0.5)
				(island_removal_mode 0)
			)
			(polygon
				(pts
					(xy 37.7825 41.91) (xy 37.6555 41.91) (xy 37.6555 41.402) (xy 37.7825 41.402)
				)
			)
		)
	)
	(footprint ""
		(layer "F.Cu")
		(at 3.429 31.75)
		(property "Reference" "TP48"
			(at 1.67767 1.778 90)
			(unlocked yes)
			(layer "F.SilkS")
			(effects
				(font
					(size 0.7874 0.5842)
					(thickness 0.127)
				)
				(justify left)
			)
		)
		(property "Value" "*"
			(at -0.4826 -0.14732 0)
			(unlocked yes)
			(layer "F.Fab")
			(hide yes)
			(effects
				(font
					(size 1.27 0.9652)
					(thickness 0.000001)
				)
				(justify left)
			)
		)
		(property "Device Type" "TP_SMALL"
			(at -0.4826 -0.14732 0)
			(unlocked yes)
			(layer "F.Fab")
			(hide yes)
			(effects
				(font
					(size 1.27 0.9652)
					(thickness 0.000001)
				)
				(justify left)
			)
		)
		(duplicate_pad_numbers_are_jumpers no)
		(fp_line
			(start -0.8636 -0.8636)
			(end -0.8636 0.8636)
			(stroke
				(width 0.1524)
				(type default)
			)
			(layer "F.SilkS")
		)
		(fp_line
			(start -0.8636 0.8636)
			(end 0.8636 0.8636)
			(stroke
				(width 0.1524)
				(type default)
			)
			(layer "F.SilkS")
		)
		(fp_line
			(start 0.8636 -0.8636)
			(end -0.8636 -0.8636)
			(stroke
				(width 0.1524)
				(type default)
			)
			(layer "F.SilkS")
		)
		(fp_line
			(start 0.8636 0.8636)
			(end 0.8636 -0.8636)
			(stroke
				(width 0.1524)
				(type default)
			)
			(layer "F.SilkS")
		)
		(fp_poly
			(pts
				(xy -0.635 -0.635) (xy -0.635 0.635) (xy 0.635 0.635) (xy 0.635 -0.635)
			)
			(stroke
				(width 0)
				(type default)
			)
			(fill no)
			(layer "F.CrtYd")
		)
		(pad "1" smd rect
			(at 0 0)
			(size 1.27 1.27)
			(layers "F.Cu" "F.Mask" "F.Paste")
			(net "VDD_1.2V")
		)
	)
	(footprint ""
		(layer "F.Cu")
		(at 25.908 37.719 90)
		(property "Reference" "R88"
			(at 0 0 90)
			(layer "F.SilkS")
			(hide yes)
			(effects
				(font
					(size 1.27 1.27)
				)
			)
		)
		(property "Value" "4.75K"
			(at -0.148158 1.3462 180)
			(unlocked yes)
			(layer "F.Fab")
			(hide yes)
			(effects
				(font
					(size 1.27 0.9652)
					(thickness 0.000001)
				)
				(justify left)
			)
		)
		(property "Device Type" "REST4024"
			(at -0.148158 1.3462 180)
			(unlocked yes)
			(layer "F.Fab")
			(hide yes)
			(effects
				(font
					(size 1.27 0.9652)
					(thickness 0.000001)
				)
				(justify left)
			)
		)
		(duplicate_pad_numbers_are_jumpers no)
		(fp_poly
			(pts
				(xy 0.635 1.0668) (xy 0.635 -1.0668) (xy -0.635 -1.0668) (xy -0.635 1.0668)
			)
			(stroke
				(width 0)
				(type default)
			)
			(fill no)
			(layer "F.CrtYd")
		)
		(fp_line
			(start 0.254 -0.508)
			(end 0.254 0.508)
			(stroke
				(width 0.0254)
				(type default)
			)
			(layer "F.Fab")
		)
		(fp_line
			(start -0.254 -0.508)
			(end 0.254 -0.508)
			(stroke
				(width 0.0254)
				(type default)
			)
			(layer "F.Fab")
		)
		(fp_line
			(start 0.254 0.508)
			(end -0.254 0.508)
			(stroke
				(width 0.0254)
				(type default)
			)
			(layer "F.Fab")
		)
		(fp_line
			(start -0.254 0.508)
			(end -0.254 -0.508)
			(stroke
				(width 0.0254)
				(type default)
			)
			(layer "F.Fab")
		)
		(pad "1" smd rect
			(at 0 -0.4191 90)
			(size 0.508 0.5334)
			(layers "F.Cu" "F.Mask" "F.Paste")
			(net "GND")
		)
		(pad "2" smd rect
			(at 0 0.4191 90)
			(size 0.508 0.5334)
			(layers "F.Cu" "F.Mask" "F.Paste")
			(net "VDD_CORE_EN")
		)
		(zone
			(layer "F.Cu")
			(hatch none 0.5)
			(connect_pads
				(clearance 0)
			)
			(min_thickness 0.25)
			(keepout
				(tracks not_allowed)
				(vias allowed)
				(pads allowed)
				(copperpour not_allowed)
				(footprints allowed)
			)
			(placement
				(enabled no)
				(sheetname "")
			)
			(fill
				(thermal_gap 0.5)
				(thermal_bridge_width 0.5)
				(island_removal_mode 0)
			)
			(polygon
				(pts
					(xy 25.8826 37.6936) (xy 25.9334 37.6936) (xy 25.9334 37.7444) (xy 25.8826 37.7444)
				)
			)
		)
	)
	(footprint ""
		(layer "F.Cu")
		(at 30.988 32.639 180)
		(property "Reference" "R94"
			(at 0 0 180)
			(layer "F.SilkS")
			(hide yes)
			(effects
				(font
					(size 1.27 1.27)
				)
			)
		)
		(property "Value" "4.75K"
			(at -0.148158 1.3462 270)
			(unlocked yes)
			(layer "F.Fab")
			(hide yes)
			(effects
				(font
					(size 1.27 0.9652)
					(thickness 0.000001)
				)
				(justify left)
			)
		)
		(property "Device Type" "REST4024"
			(at -0.148158 1.3462 270)
			(unlocked yes)
			(layer "F.Fab")
			(hide yes)
			(effects
				(font
					(size 1.27 0.9652)
					(thickness 0.000001)
				)
				(justify left)
			)
		)
		(duplicate_pad_numbers_are_jumpers no)
		(fp_poly
			(pts
				(xy 0.635 1.0668) (xy 0.635 -1.0668) (xy -0.635 -1.0668) (xy -0.635 1.0668)
			)
			(stroke
				(width 0)
				(type default)
			)
			(fill no)
			(layer "F.CrtYd")
		)
		(fp_line
			(start 0.254 0.508)
			(end -0.254 0.508)
			(stroke
				(width 0.0254)
				(type default)
			)
			(layer "F.Fab")
		)
		(fp_line
			(start 0.254 -0.508)
			(end 0.254 0.508)
			(stroke
				(width 0.0254)
				(type default)
			)
			(layer "F.Fab")
		)
		(fp_line
			(start -0.254 0.508)
			(end -0.254 -0.508)
			(stroke
				(width 0.0254)
				(type default)
			)
			(layer "F.Fab")
		)
		(fp_line
			(start -0.254 -0.508)
			(end 0.254 -0.508)
			(stroke
				(width 0.0254)
				(type default)
			)
			(layer "F.Fab")
		)
		(pad "1" smd rect
			(at 0 -0.4191 180)
			(size 0.508 0.5334)
			(layers "F.Cu" "F.Mask" "F.Paste")
			(net "_NFP_CORE_VID3")
		)
		(pad "2" smd rect
			(at 0 0.4191 180)
			(size 0.508 0.5334)
			(layers "F.Cu" "F.Mask" "F.Paste")
			(net "VDD_1.2V")
		)
		(zone
			(layer "F.Cu")
			(hatch none 0.5)
			(connect_pads
				(clearance 0)
			)
			(min_thickness 0.25)
			(keepout
				(tracks not_allowed)
				(vias allowed)
				(pads allowed)
				(copperpour not_allowed)
				(footprints allowed)
			)
			(placement
				(enabled no)
				(sheetname "")
			)
			(fill
				(thermal_gap 0.5)
				(thermal_bridge_width 0.5)
				(island_removal_mode 0)
			)
			(polygon
				(pts
					(xy 30.9626 32.6644) (xy 30.9626 32.6136) (xy 31.0134 32.6136) (xy 31.0134 32.6644)
				)
			)
		)
	)
)
